#ISCELL
  mstr_misc dns *
  *
#ISCELL
  pure_quanta quanta_title_block_c *
  *
#CELL
  pure_quanta pt5161lrs *
  page400_i1
#CELL
  pure_quanta q_res *
  page400_i102
#CELL
  pure_quanta q_res *
  page400_i103
#CELL
  pure_quanta q_res *
  page400_i105
#CELL
  pure_quanta q_res *
  page400_i106
#CELL
  pure_quanta pt5161lrs *
  page400_i2
#ISCELL
  pure_quanta_power p1v0 *
  page400_i21
#ISCELL
  pure_quanta_power universal_gnd *
  page400_i25
#ISCELL
  pure_quanta_power p1v0 *
  page400_i27
#ISCELL
  pure_quanta_power universal_gnd *
  page400_i3
#ISCELL
  pure_quanta_power universal_gnd *
  page400_i4
#ISCELL
  pure_quanta_power vcc_core *
  page400_i40
#ISCELL
  pure_quanta_power universal_gnd *
  page400_i6
#ISCELL
  pure_quanta_power p1v0 *
  page400_i61
#ISCELL
  pure_quanta_power universal_gnd *
  page400_i8
#ISCELL
  pure_quanta_power vcc_core *
  page400_i97
#ISCELL
  pure_quanta_power p1v0 *
  page400_i98
